(kicad_pcb
	(version 20260206)
	(generator "pcbnew")
	(generator_version "10.0")
	(general
		(thickness 1.6)
		(legacy_teardrops no)
	)
	(paper "A4")
	(title_block
		(title "Bryce Canyon_F.DPB_16315-1-OCP.brd")
		(comment 1 "Bryce Canyon / footprints 1576-1578 of 2223")
	)
	(layers
		(0 "F.Cu" signal "TOP")
		(4 "In1.Cu" signal "L2GND")
		(6 "In2.Cu" signal "L3")
		(8 "In3.Cu" signal "L4GND")
		(10 "In4.Cu" signal "L5")
		(12 "In5.Cu" signal "L6VCC")
		(14 "In6.Cu" signal "L7VCC")
		(16 "In7.Cu" signal "L8")
		(18 "In8.Cu" signal "L9GND")
		(20 "In9.Cu" signal "L10")
		(22 "In10.Cu" signal "L11GND")
		(2 "B.Cu" signal "BOTTOM")
		(9 "F.Adhes" user "F.Adhesive")
		(11 "B.Adhes" user "B.Adhesive")
		(13 "F.Paste" user "Package Geometry/Pastemask Top")
		(15 "B.Paste" user "Package Geometry/Pastemask Bottom")
		(5 "F.SilkS" user "Ref Des/Silkscreen Top")
		(7 "B.SilkS" user "Ref Des/Silkscreen Bottom")
		(1 "F.Mask" user "Board Geometry/Soldermask Top")
		(3 "B.Mask" user "Board Geometry/Soldermask Bottom")
		(17 "Dwgs.User" user "User.Drawings")
		(19 "Cmts.User" user "User.Comments")
		(21 "Eco1.User" user "User.Eco1")
		(23 "Eco2.User" user "User.Eco2")
		(25 "Edge.Cuts" user "Board Geometry/Outline")
		(27 "Margin" user)
		(31 "F.CrtYd" user "Package Geometry/Place Bound Top")
		(29 "B.CrtYd" user "Package Geometry/Place Bound Bottom")
		(35 "F.Fab" user "Ref Des/Assembly Top")
		(33 "B.Fab" user "Ref Des/Assembly Bottom")
	)
	(footprint ""
		(layer "F.Cu")
		(at 91.300046 -287.910016 -90)
		(property "Reference" "HDDSAS2"
			(at 0 0 270)
			(layer "F.SilkS")
			(hide yes)
			(effects
				(font
					(size 1.27 1.27)
				)
			)
		)
		(property "Value" "SKT-SAS15P-14P-45-GP"
			(at -20.7645 -8.9789 270)
			(unlocked yes)
			(layer "F.Fab")
			(hide yes)
			(effects
				(font
					(size 1.016 1.016)
					(thickness 0.1524)
				)
			)
		)
		(property "Device Type" "10120818-001C-TRLF"
			(at -20.7645 -10.5029 270)
			(unlocked yes)
			(layer "F.Fab")
			(hide yes)
			(effects
				(font
					(size 1.016 1.016)
					(thickness 0.1524)
				)
			)
		)
		(duplicate_pad_numbers_are_jumpers no)
		(fp_line
			(start 1.651 4.2926)
			(end 1.651 3.0099)
			(stroke
				(width 0.1524)
				(type default)
			)
			(layer "F.SilkS")
		)
		(fp_line
			(start 8.509 4.2926)
			(end 1.651 4.2926)
			(stroke
				(width 0.1524)
				(type default)
			)
			(layer "F.SilkS")
		)
		(fp_line
			(start -23.4188 3.0099)
			(end -23.4188 -3.2512)
			(stroke
				(width 0.1524)
				(type default)
			)
			(layer "F.SilkS")
		)
		(fp_line
			(start 1.651 3.0099)
			(end -23.4188 3.0099)
			(stroke
				(width 0.1524)
				(type default)
			)
			(layer "F.SilkS")
		)
		(fp_line
			(start 8.509 3.0099)
			(end 8.509 4.2926)
			(stroke
				(width 0.1524)
				(type default)
			)
			(layer "F.SilkS")
		)
		(fp_line
			(start 23.4188 3.0099)
			(end 8.509 3.0099)
			(stroke
				(width 0.1524)
				(type default)
			)
			(layer "F.SilkS")
		)
		(fp_line
			(start -23.4188 -3.2512)
			(end 23.4188 -3.2512)
			(stroke
				(width 0.1524)
				(type default)
			)
			(layer "F.SilkS")
		)
		(fp_line
			(start 23.4188 -3.2512)
			(end 23.4188 3.0099)
			(stroke
				(width 0.1524)
				(type default)
			)
			(layer "F.SilkS")
		)
		(fp_line
			(start 15.5067 -3.3401)
			(end 16.2687 -3.3401)
			(stroke
				(width 0.3302)
				(type default)
			)
			(layer "F.SilkS")
		)
		(fp_poly
			(pts
				(xy 15.868904 -3.230372) (xy 16.503904 -3.865372) (xy 15.233904 -3.865372)
			)
			(stroke
				(width 0)
				(type default)
			)
			(fill yes)
			(layer "F.SilkS")
		)
		(fp_poly
			(pts
				(xy -22.8727 -2.7559) (xy 22.8727 -2.7559) (xy 22.8727 2.7559) (xy 8.255 2.7559) (xy 8.255 3.5179)
				(xy 1.905 3.5179) (xy 1.905 2.7559) (xy -22.8727 2.7559)
			)
			(stroke
				(width 0)
				(type default)
			)
			(fill no)
			(layer "F.CrtYd")
		)
		(fp_poly
			(pts
				(xy 1.397 4.5466) (xy 1.397 3.2639) (xy -23.6728 3.2639) (xy -23.6728 -3.5052) (xy 23.6728 -3.5052)
				(xy 23.6728 -0.00635) (xy 22.8727 -0.00635) (xy 22.8727 -2.7559) (xy -22.8727 -2.7559) (xy -22.8727 2.7559)
				(xy 1.905 2.7559) (xy 1.905 3.5179) (xy 8.255 3.5179) (xy 8.255 2.7559) (xy 22.8727 2.7559) (xy 22.8727 0.00635)
				(xy 23.6728 0.00635) (xy 23.6728 3.2639) (xy 8.763 3.2639) (xy 8.763 4.5466)
			)
			(stroke
				(width 0)
				(type default)
			)
			(fill no)
			(layer "F.CrtYd")
		)
		(fp_poly
			(pts
				(xy 1.397 4.5466) (xy 1.397 3.2639) (xy -23.6728 3.2639) (xy -23.6728 -3.5052) (xy 23.6728 -3.5052)
				(xy 23.6728 3.2639) (xy 8.763 3.2639) (xy 8.763 4.5466)
			)
			(stroke
				(width 0)
				(type default)
			)
			(fill no)
			(layer "F.Fab")
		)
		(pad "" np_thru_hole circle
			(at -18.874994 0 270)
			(size 0.254 0.254)
			(drill 1.3462)
			(layers "*.Cu" "*.Mask")
			(clearance 0.9017)
			(thermal_gap 0.9017)
		)
		(pad "" np_thru_hole circle
			(at 18.874994 0 270)
			(size 0.254 0.254)
			(drill 0.9398)
			(layers "*.Cu" "*.Mask")
			(clearance 0.6985)
			(thermal_gap 0.6985)
		)
		(pad "G1" smd rect
			(at 21.874988 0 270)
			(size 2.5908 2.5908)
			(layers "F.Cu" "F.Mask" "F.Paste")
			(net "GND")
		)
		(pad "G2" smd rect
			(at -21.874988 0 270)
			(size 2.5908 2.5908)
			(layers "F.Cu" "F.Mask" "F.Paste")
			(net "GND")
		)
		(pad "P1" smd rect
			(at 1.905 -1.82499 270)
			(size 0.6096 2.3622)
			(layers "F.Cu" "F.Mask" "F.Paste")
			(net "Net_2066")
		)
		(pad "P2" smd rect
			(at 0.635 -1.82499 270)
			(size 0.6096 2.3622)
			(layers "F.Cu" "F.Mask" "F.Paste")
			(net "Net_2067")
		)
		(pad "P3" smd rect
			(at -0.635 -1.82499 270)
			(size 0.6096 2.3622)
			(layers "F.Cu" "F.Mask" "F.Paste")
			(net "Net_2068")
		)
		(pad "P4" smd rect
			(at -1.905 -1.82499 270)
			(size 0.6096 2.3622)
			(layers "F.Cu" "F.Mask" "F.Paste")
			(net "GND")
		)
		(pad "P5" smd rect
			(at -3.175 -1.82499 270)
			(size 0.6096 2.3622)
			(layers "F.Cu" "F.Mask" "F.Paste")
			(net "HDD_PRSNT_2")
		)
		(pad "P6" smd rect
			(at -4.445 -1.82499 270)
			(size 0.6096 2.3622)
			(layers "F.Cu" "F.Mask" "F.Paste")
			(net "GND")
		)
		(pad "P7" smd rect
			(at -5.715 -1.82499 270)
			(size 0.6096 2.3622)
			(layers "F.Cu" "F.Mask" "F.Paste")
			(net "5V_PRE_2")
		)
		(pad "P8" smd rect
			(at -6.985 -1.82499 270)
			(size 0.6096 2.3622)
			(layers "F.Cu" "F.Mask" "F.Paste")
			(net "P5V_HDD2")
		)
		(pad "P9" smd rect
			(at -8.255 -1.82499 270)
			(size 0.6096 2.3622)
			(layers "F.Cu" "F.Mask" "F.Paste")
			(net "P5V_HDD2")
		)
		(pad "P10" smd rect
			(at -9.525 -1.82499 270)
			(size 0.6096 2.3622)
			(layers "F.Cu" "F.Mask" "F.Paste")
			(net "GND")
		)
		(pad "P11" smd rect
			(at -10.795 -1.82499 270)
			(size 0.6096 2.3622)
			(layers "F.Cu" "F.Mask" "F.Paste")
			(net "ACT_HDD_2")
		)
		(pad "P12" smd rect
			(at -12.065 -1.82499 270)
			(size 0.6096 2.3622)
			(layers "F.Cu" "F.Mask" "F.Paste")
			(net "GND")
		)
		(pad "P13" smd rect
			(at -13.335 -1.82499 270)
			(size 0.6096 2.3622)
			(layers "F.Cu" "F.Mask" "F.Paste")
			(net "12V_PRE_2")
		)
		(pad "P14" smd rect
			(at -14.605 -1.82499 270)
			(size 0.6096 2.3622)
			(layers "F.Cu" "F.Mask" "F.Paste")
			(net "P12V_HDD2")
		)
		(pad "P15" smd rect
			(at -15.875 -1.82499 270)
			(size 0.6096 2.3622)
			(layers "F.Cu" "F.Mask" "F.Paste")
			(net "P12V_HDD2")
		)
		(pad "S1" smd rect
			(at 15.875 -1.82499 270)
			(size 0.6096 2.3622)
			(layers "F.Cu" "F.Mask" "F.Paste")
			(net "GND")
		)
		(pad "S2" smd rect
			(at 14.605 -1.82499 270)
			(size 0.6096 2.3622)
			(layers "F.Cu" "F.Mask" "F.Paste")
			(net "SAS_HDD_RX_P2")
		)
		(pad "S3" smd rect
			(at 13.335 -1.82499 270)
			(size 0.6096 2.3622)
			(layers "F.Cu" "F.Mask" "F.Paste")
			(net "SAS_HDD_RX_N2")
		)
		(pad "S4" smd rect
			(at 12.065 -1.82499 270)
			(size 0.6096 2.3622)
			(layers "F.Cu" "F.Mask" "F.Paste")
			(net "GND")
		)
		(pad "S5" smd rect
			(at 10.795 -1.82499 270)
			(size 0.6096 2.3622)
			(layers "F.Cu" "F.Mask" "F.Paste")
			(net "PHY_DRV_A_TO_SCC_A_2_DN")
		)
		(pad "S6" smd rect
			(at 9.525 -1.82499 270)
			(size 0.6096 2.3622)
			(layers "F.Cu" "F.Mask" "F.Paste")
			(net "PHY_DRV_A_TO_SCC_A_2_DP")
		)
		(pad "S7" smd rect
			(at 8.255 -1.82499 270)
			(size 0.6096 2.3622)
			(layers "F.Cu" "F.Mask" "F.Paste")
			(net "GND")
		)
		(pad "S8" smd rect
			(at 7.480046 2.845054 270)
			(size 0.508 2.3622)
			(layers "F.Cu" "F.Mask" "F.Paste")
			(net "GND")
		)
		(pad "S9" smd rect
			(at 6.679946 2.845054 270)
			(size 0.508 2.3622)
			(layers "F.Cu" "F.Mask" "F.Paste")
			(net "Net_467")
		)
		(pad "S10" smd rect
			(at 5.8801 2.845054 270)
			(size 0.508 2.3622)
			(layers "F.Cu" "F.Mask" "F.Paste")
			(net "Net_359")
		)
		(pad "S11" smd rect
			(at 5.08 2.845054 270)
			(size 0.508 2.3622)
			(layers "F.Cu" "F.Mask" "F.Paste")
			(net "GND")
		)
		(pad "S12" smd rect
			(at 4.2799 2.845054 270)
			(size 0.508 2.3622)
			(layers "F.Cu" "F.Mask" "F.Paste")
			(net "Net_395")
		)
		(pad "S13" smd rect
			(at 3.480054 2.845054 270)
			(size 0.508 2.3622)
			(layers "F.Cu" "F.Mask" "F.Paste")
			(net "Net_431")
		)
		(pad "S14" smd rect
			(at 2.679954 2.845054 270)
			(size 0.508 2.3622)
			(layers "F.Cu" "F.Mask" "F.Paste")
			(net "GND")
		)
		(zone
			(layer "F.Cu")
			(hatch none 0.5)
			(connect_pads
				(clearance 0)
			)
			(min_thickness 0.25)
			(keepout
				(tracks allowed)
				(vias not_allowed)
				(pads allowed)
				(copperpour not_allowed)
				(footprints allowed)
			)
			(placement
				(enabled no)
				(sheetname "")
			)
			(fill
				(thermal_gap 0.5)
				(thermal_bridge_width 0.5)
				(island_removal_mode 0)
			)
			(polygon
				(pts
					(xy 94.957646 -304.648616) (xy 87.883746 -304.648616) (xy 87.883746 -311.582816) (xy 88.988646 -311.582816)
					(xy 88.988646 -307.468016) (xy 93.611446 -307.468016) (xy 93.611446 -311.582816) (xy 94.957646 -311.582816)
				)
			)
		)
		(zone
			(layer "F.Cu")
			(hatch none 0.5)
			(connect_pads
				(clearance 0)
			)
			(min_thickness 0.25)
			(keepout
				(tracks not_allowed)
				(vias allowed)
				(pads allowed)
				(copperpour not_allowed)
				(footprints allowed)
			)
			(placement
				(enabled no)
				(sheetname "")
			)
			(fill
				(thermal_gap 0.5)
				(thermal_bridge_width 0.5)
				(island_removal_mode 0)
			)
			(polygon
				(pts
					(xy 94.957646 -304.648616) (xy 87.883746 -304.648616) (xy 87.883746 -311.582816) (xy 88.988646 -311.582816)
					(xy 88.988646 -307.468016) (xy 93.611446 -307.468016) (xy 93.611446 -311.582816) (xy 94.957646 -311.582816)
				)
			)
		)
		(zone
			(layer "F.Cu")
			(hatch none 0.5)
			(connect_pads
				(clearance 0)
			)
			(min_thickness 0.25)
			(keepout
				(tracks allowed)
				(vias not_allowed)
				(pads allowed)
				(copperpour not_allowed)
				(footprints allowed)
			)
			(placement
				(enabled no)
				(sheetname "")
			)
			(fill
				(thermal_gap 0.5)
				(thermal_bridge_width 0.5)
				(island_removal_mode 0)
			)
			(polygon
				(pts
					(xy 94.957646 -271.171416) (xy 87.883746 -271.171416) (xy 87.883746 -264.237216) (xy 88.988646 -264.237216)
					(xy 88.988646 -268.352016) (xy 93.611446 -268.352016) (xy 93.611446 -264.237216) (xy 94.957646 -264.237216)
				)
			)
		)
		(zone
			(layer "F.Cu")
			(hatch none 0.5)
			(connect_pads
				(clearance 0)
			)
			(min_thickness 0.25)
			(keepout
				(tracks not_allowed)
				(vias allowed)
				(pads allowed)
				(copperpour not_allowed)
				(footprints allowed)
			)
			(placement
				(enabled no)
				(sheetname "")
			)
			(fill
				(thermal_gap 0.5)
				(thermal_bridge_width 0.5)
				(island_removal_mode 0)
			)
			(polygon
				(pts
					(xy 94.957646 -271.171416) (xy 87.883746 -271.171416) (xy 87.883746 -264.237216) (xy 88.988646 -264.237216)
					(xy 88.988646 -268.352016) (xy 93.611446 -268.352016) (xy 93.611446 -264.237216) (xy 94.957646 -264.237216)
				)
			)
		)
		(zone
			(layers "F.Cu" "B.Cu" "In1.Cu" "In2.Cu" "In3.Cu" "In4.Cu" "In5.Cu" "In6.Cu"
				"In7.Cu" "In8.Cu" "In9.Cu" "In10.Cu"
			)
			(hatch none 0.5)
			(connect_pads
				(clearance 0)
			)
			(min_thickness 0.25)
			(keepout
				(tracks not_allowed)
				(vias allowed)
				(pads allowed)
				(copperpour not_allowed)
				(footprints allowed)
			)
			(placement
				(enabled no)
				(sheetname "")
			)
			(fill
				(thermal_gap 0.5)
				(thermal_bridge_width 0.5)
				(island_removal_mode 0)
			)
			(polygon
				(pts
					(arc
						(start 92.074746 -269.035022)
						(mid 90.525346 -269.035022)
						(end 92.074746 -269.035022)
					)
				)
			)
		)
		(zone
			(layers "F.Cu" "B.Cu" "In1.Cu" "In2.Cu" "In3.Cu" "In4.Cu" "In5.Cu" "In6.Cu"
				"In7.Cu" "In8.Cu" "In9.Cu" "In10.Cu"
			)
			(hatch none 0.5)
			(connect_pads
				(clearance 0)
			)
			(min_thickness 0.25)
			(keepout
				(tracks not_allowed)
				(vias allowed)
				(pads allowed)
				(copperpour not_allowed)
				(footprints allowed)
			)
			(placement
				(enabled no)
				(sheetname "")
			)
			(fill
				(thermal_gap 0.5)
				(thermal_bridge_width 0.5)
				(island_removal_mode 0)
			)
			(polygon
				(pts
					(arc
						(start 92.277946 -306.78501)
						(mid 90.322146 -306.78501)
						(end 92.277946 -306.78501)
					)
				)
			)
		)
	)
	(footprint ""
		(layer "F.Cu")
		(at 270.489172 -238.924846 180)
		(property "Reference" "R440"
			(at 0 0 180)
			(layer "F.SilkS")
			(hide yes)
			(effects
				(font
					(size 1.27 1.27)
				)
			)
		)
		(property "Value" "1KR2F-3-GP"
			(at 0.064008 -3.993896 180)
			(unlocked yes)
			(layer "F.Fab")
			(hide yes)
			(effects
				(font
					(size 1.016 1.016)
					(thickness 0.1524)
				)
			)
		)
		(property "Device Type" "R402H16"
			(at 0.064008 -5.517896 180)
			(unlocked yes)
			(layer "F.Fab")
			(hide yes)
			(effects
				(font
					(size 1.016 1.016)
					(thickness 0.1524)
				)
			)
		)
		(duplicate_pad_numbers_are_jumpers no)
		(fp_line
			(start 0.508 -0.9398)
			(end -0.508 -0.9398)
			(stroke
				(width 0.1524)
				(type default)
			)
			(layer "F.SilkS")
		)
		(fp_line
			(start -0.508 -0.9398)
			(end -0.508 0.9398)
			(stroke
				(width 0.1524)
				(type default)
			)
			(layer "F.SilkS")
		)
		(fp_rect
			(start -0.508 0.9398)
			(end 0.508 -0.9398)
			(stroke
				(width 0)
				(type default)
			)
			(fill no)
			(layer "F.CrtYd")
		)
		(fp_rect
			(start -0.508 0.9398)
			(end 0.508 -0.9398)
			(stroke
				(width 0)
				(type default)
			)
			(fill no)
			(layer "F.Fab")
		)
		(pad "1" smd custom
			(at 0 -0.4445 180)
			(size 0.1397 0.1397)
			(layers "F.Cu" "F.Mask" "F.Paste")
			(net "P3V3_STBY_A")
			(options
				(clearance outline)
				(anchor circle)
			)
			(primitives
				(gr_poly
					(pts
						(arc
							(start -0.1778 -0.2794)
							(mid -0.249642 -0.249642)
							(end -0.2794 -0.1778)
						)
						(arc
							(start -0.2794 0.1778)
							(mid -0.249642 0.249642)
							(end -0.1778 0.2794)
						)
						(arc
							(start 0.1778 0.2794)
							(mid 0.249642 0.249642)
							(end 0.2794 0.1778)
						)
						(arc
							(start 0.2794 -0.1778)
							(mid 0.249642 -0.249642)
							(end 0.1778 -0.2794)
						)
					)
					(width 0)
					(fill yes)
				)
			)
		)
		(pad "2" smd custom
			(at 0 0.4445 180)
			(size 0.1397 0.1397)
			(layers "F.Cu" "F.Mask" "F.Paste")
			(net "I2C_BMC_A_EXP_A_SDA")
			(options
				(clearance outline)
				(anchor circle)
			)
			(primitives
				(gr_poly
					(pts
						(arc
							(start -0.1778 -0.2794)
							(mid -0.249642 -0.249642)
							(end -0.2794 -0.1778)
						)
						(arc
							(start -0.2794 0.1778)
							(mid -0.249642 0.249642)
							(end -0.1778 0.2794)
						)
						(arc
							(start 0.1778 0.2794)
							(mid 0.249642 0.249642)
							(end 0.2794 0.1778)
						)
						(arc
							(start 0.2794 -0.1778)
							(mid 0.249642 -0.249642)
							(end 0.1778 -0.2794)
						)
					)
					(width 0)
					(fill yes)
				)
			)
		)
	)
	(footprint ""
		(layer "F.Cu")
		(at 178.2318 -163.935918 180)
		(property "Reference" "Q103"
			(at 0 0 180)
			(layer "F.SilkS")
			(hide yes)
			(effects
				(font
					(size 1.27 1.27)
				)
			)
		)
		(property "Value" "2N7002KDW-GP"
			(at -2.3622 -8.2042 180)
			(unlocked yes)
			(layer "F.Fab")
			(hide yes)
			(effects
				(font
					(size 1.016 1.016)
					(thickness 0.1524)
				)
			)
		)
		(property "Device Type" "SOT-363H44"
			(at -2.3622 -10.1092 180)
			(unlocked yes)
			(layer "F.Fab")
			(hide yes)
			(effects
				(font
					(size 1.016 1.016)
					(thickness 0.1524)
				)
			)
		)
		(duplicate_pad_numbers_are_jumpers no)
		(fp_line
			(start 1.4478 1.7018)
			(end 1.4478 -1.7018)
			(stroke
				(width 0.1524)
				(type default)
			)
			(layer "F.SilkS")
		)
		(fp_line
			(start 1.4478 -1.7018)
			(end -1.4478 -1.7018)
			(stroke
				(width 0.1524)
				(type default)
			)
			(layer "F.SilkS")
		)
		(fp_line
			(start -1.27 1.524)
			(end -1.27 0.6604)
			(stroke
				(width 0.4826)
				(type default)
			)
			(layer "F.SilkS")
		)
		(fp_line
			(start -1.4478 1.7018)
			(end 1.4478 1.7018)
			(stroke
				(width 0.1524)
				(type default)
			)
			(layer "F.SilkS")
		)
		(fp_line
			(start -1.4478 -1.7018)
			(end -1.4478 1.7018)
			(stroke
				(width 0.1524)
				(type default)
			)
			(layer "F.SilkS")
		)
		(fp_poly
			(pts
				(xy -1.524 -1.778) (xy 1.524 -1.778) (xy 1.524 1.778) (xy -1.524 1.778)
			)
			(stroke
				(width 0)
				(type default)
			)
			(fill no)
			(layer "F.CrtYd")
		)
		(fp_poly
			(pts
				(xy -1.524 -1.778) (xy 1.524 -1.778) (xy 1.524 1.778) (xy -1.524 1.778)
			)
			(stroke
				(width 0)
				(type default)
			)
			(fill no)
			(layer "F.Fab")
		)
		(pad "1" smd rect
			(at -0.65024 0.9398 180)
			(size 0.4064 1.016)
			(layers "F.Cu" "F.Mask" "F.Paste")
			(net "GND")
		)
		(pad "2" smd rect
			(at 0 0.9398 180)
			(size 0.4064 1.016)
			(layers "F.Cu" "F.Mask" "F.Paste")
			(net "SW_PWR_R_HDD17")
		)
		(pad "3" smd rect
			(at 0.65024 0.9398 180)
			(size 0.4064 1.016)
			(layers "F.Cu" "F.Mask" "F.Paste")
			(net "SW_HDD_P17")
		)
		(pad "4" smd rect
			(at 0.65024 -0.9398 180)
			(size 0.4064 1.016)
			(layers "F.Cu" "F.Mask" "F.Paste")
			(net "GND")
		)
		(pad "5" smd rect
			(at 0 -0.9398 180)
			(size 0.4064 1.016)
			(layers "F.Cu" "F.Mask" "F.Paste")
			(net "SW_HDD_G17")
		)
		(pad "6" smd rect
			(at -0.65024 -0.9398 180)
			(size 0.4064 1.016)
			(layers "F.Cu" "F.Mask" "F.Paste")
			(net "SW_HDD_R17")
		)
	)
)
